FILE_TYPE = CONNECTIVITY;
{Allegro Design Entry HDL 17.2-2016 S081 (4005846) 1/11/2022}
"PAGE_NUMBER" = 96;
0"NC";
1"M_L_CPU0_SA_CB<7:0>";
2"M_L_CPU0_SA_CA<6:0>";
3"M_L_CPU0_SB_CA<6:0>";
4"M_L_CPU0_SB_CB<7:0>";
5"M_L_CPU0_SA_DQ<31:0>";
6"M_L_CPU0_SB_DQ<31:0>";
7"M_L_CPU0_SA_DQS_DN<9:0>";
8"M_L_CPU0_SA_DQS_DP<9:0>";
9"M_L_CPU0_SB_DQS_DN<9:0>";
10"M_L_CPU0_SB_DQS_DP<9:0>";
11"GND\g";
12"GND\g";
13"P3V3_STBY\g";
14"I3C_SPD_DDRGL_CPU0_SCL";
15"I3C_SPD_DDRL_CPU0_SCL";
16"I3C_SPD_DDRGL_CPU0_SDA";
17"PD_CHL_CPU0_DIMM_SAA";
18"P3V3_STBY\g";
19"PWRGD_CHL_CPU0_DIMM";
20"TP_CHL_CPU0_DIMM_RFU_6";
21"M_L_CPU0_ALERT_N";
22"M_L_CPU0_RESET_N";
23"M_L_CPU0_SB_RSP<0>";
24"TP_CHL_CPU0_DIMM_RFU_1";
25"TP_CHL_CPU0_DIMM_RFU_0";
26"TP_CHL_CPU0_DIMM_RFU_4";
27"TP_CHL_CPU0_DIMM_RFU_3";
28"TP_CHL_CPU0_DIMM_RFU_2";
29"M_L_CPU0_SA_RSP<0>";
30"PWRGD_CHGL_CPU0";
31"GND\g";
32"P12V_MEM_0\g";
33"GND\g";
34"M_L_CPU0_SB_DQS_DP<9>";
35"M_L_CPU0_SB_DQS_DN<9>";
36"M_L_CPU0_SA_DQS_DP<9>";
37"M_L_CPU0_SA_DQS_DN<9>";
38"M_L_CPU0_SA_DQS_DP<8>";
39"M_L_CPU0_SA_DQS_DN<8>";
40"M_L_CPU0_SB_DQS_DN<7>";
41"M_L_CPU0_SA_DQS_DP<7>";
42"M_L_CPU0_SB_DQS_DP<6>";
43"M_L_CPU0_SB_DQS_DN<6>";
44"M_L_CPU0_SA_DQS_DN<6>";
45"M_L_CPU0_SB_DQS_DP<5>";
46"M_L_CPU0_SB_DQS_DN<5>";
47"M_L_CPU0_SA_DQS_DP<5>";
48"M_L_CPU0_SA_DQS_DN<5>";
49"M_L_CPU0_SB_DQS_DP<4>";
50"M_L_CPU0_SB_DQS_DN<4>";
51"M_L_CPU0_SA_DQS_DP<4>";
52"M_L_CPU0_SA_DQS_DN<4>";
53"M_L_CPU0_SB_DQS_DP<3>";
54"M_L_CPU0_SB_DQS_DN<3>";
55"M_L_CPU0_SA_DQS_DP<3>";
56"M_L_CPU0_SA_DQS_DN<3>";
57"M_L_CPU0_SB_DQS_DP<2>";
58"M_L_CPU0_SB_DQS_DN<2>";
59"M_L_CPU0_SA_DQS_DP<2>";
60"M_L_CPU0_SA_DQS_DN<2>";
61"M_L_CPU0_SB_DQS_DP<1>";
62"M_L_CPU0_SB_DQS_DN<1>";
63"M_L_CPU0_SA_DQS_DP<1>";
64"M_L_CPU0_SA_DQS_DN<1>";
65"M_L_CPU0_SB_DQS_DP<0>";
66"M_L_CPU0_SB_DQS_DN<0>";
67"M_L_CPU0_SA_DQS_DP<0>";
68"M_L_CPU0_SA_DQS_DN<0>";
69"M_L_CPU0_SB_DQS_DP<7>";
70"M_L_CPU0_SB_DQS_DN<8>";
71"M_L_CPU0_SB_DQS_DP<8>";
72"M_L_CPU0_SA_DQS_DP<6>";
73"M_L_CPU0_SA_DQS_DN<7>";
74"M_L_CPU0_SA_DQ<18>";
75"M_L_CPU0_SA_DQ<30>";
76"M_L_CPU0_SA_DQ<31>";
77"TP_CHL_CPU0_DIMM_RFU_5";
78"M_L_CPU0_SB_PAR";
79"M_L_CPU0_SA_PAR";
80"M_L_CPU0_SB_DQ<0>";
81"M_L_CPU0_SB_DQ<1>";
82"M_L_CPU0_SB_DQ<2>";
83"M_L_CPU0_SB_DQ<3>";
84"M_L_CPU0_SB_DQ<4>";
85"M_L_CPU0_SB_DQ<5>";
86"M_L_CPU0_SB_DQ<6>";
87"M_L_CPU0_SB_DQ<7>";
88"M_L_CPU0_SB_DQ<8>";
89"M_L_CPU0_SB_DQ<9>";
90"M_L_CPU0_SB_DQ<10>";
91"M_L_CPU0_SB_DQ<11>";
92"M_L_CPU0_SB_DQ<12>";
93"M_L_CPU0_SB_DQ<13>";
94"M_L_CPU0_SB_DQ<14>";
95"M_L_CPU0_SB_DQ<15>";
96"M_L_CPU0_SB_DQ<16>";
97"M_L_CPU0_SB_DQ<17>";
98"M_L_CPU0_SB_DQ<18>";
99"M_L_CPU0_SB_DQ<19>";
100"M_L_CPU0_SB_DQ<20>";
101"M_L_CPU0_SB_DQ<21>";
102"M_L_CPU0_SB_DQ<22>";
103"M_L_CPU0_SB_DQ<23>";
104"M_L_CPU0_SB_DQ<24>";
105"M_L_CPU0_SB_DQ<25>";
106"M_L_CPU0_SB_DQ<26>";
107"M_L_CPU0_SB_DQ<27>";
108"M_L_CPU0_SB_DQ<28>";
109"M_L_CPU0_SB_DQ<29>";
110"M_L_CPU0_SB_DQ<30>";
111"M_L_CPU0_SB_DQ<31>";
112"M_L_CPU0_SA_DQ<0>";
113"M_L_CPU0_SA_DQ<1>";
114"M_L_CPU0_SA_DQ<2>";
115"M_L_CPU0_SA_DQ<3>";
116"M_L_CPU0_SA_DQ<4>";
117"M_L_CPU0_SA_DQ<5>";
118"M_L_CPU0_SA_DQ<6>";
119"M_L_CPU0_SA_DQ<7>";
120"M_L_CPU0_SA_DQ<8>";
121"M_L_CPU0_SA_DQ<9>";
122"M_L_CPU0_SA_DQ<10>";
123"M_L_CPU0_SA_DQ<11>";
124"M_L_CPU0_SA_DQ<12>";
125"M_L_CPU0_SA_DQ<13>";
126"M_L_CPU0_SA_DQ<14>";
127"M_L_CPU0_SA_DQ<15>";
128"M_L_CPU0_SA_DQ<16>";
129"M_L_CPU0_SA_DQ<17>";
130"M_L_CPU0_SA_DQ<19>";
131"M_L_CPU0_SA_DQ<20>";
132"M_L_CPU0_SA_DQ<21>";
133"M_L_CPU0_SA_DQ<22>";
134"M_L_CPU0_SA_DQ<23>";
135"M_L_CPU0_SA_DQ<24>";
136"M_L_CPU0_SA_DQ<25>";
137"M_L_CPU0_SA_DQ<26>";
138"M_L_CPU0_SA_DQ<27>";
139"M_L_CPU0_SA_DQ<28>";
140"M_L_CPU0_SA_DQ<29>";
141"M_L_CPU0_SB_CS_N<1>";
142"M_L_CPU0_SA_CS_N<1>";
143"M_L_CPU0_SB_CS_N<0>";
144"M_L_CPU0_SA_CS_N<0>";
145"M_L_CPU0_CLK_DP<0>";
146"M_L_CPU0_CLK_DN<0>";
147"M_L_CPU0_SB_CB<0>";
148"M_L_CPU0_SB_CB<1>";
149"M_L_CPU0_SB_CB<2>";
150"M_L_CPU0_SB_CB<3>";
151"M_L_CPU0_SB_CB<4>";
152"M_L_CPU0_SB_CB<5>";
153"M_L_CPU0_SB_CB<6>";
154"M_L_CPU0_SA_CB<0>";
155"M_L_CPU0_SA_CB<2>";
156"M_L_CPU0_SA_CB<3>";
157"M_L_CPU0_SA_CB<5>";
158"M_L_CPU0_SA_CB<6>";
159"M_L_CPU0_SB_CA<6>";
160"M_L_CPU0_SA_CA<6>";
161"M_L_CPU0_SB_CA<5>";
162"M_L_CPU0_SA_CA<5>";
163"M_L_CPU0_SB_CA<4>";
164"M_L_CPU0_SA_CA<4>";
165"M_L_CPU0_SB_CA<3>";
166"M_L_CPU0_SA_CA<3>";
167"M_L_CPU0_SB_CA<2>";
168"M_L_CPU0_SA_CA<2>";
169"M_L_CPU0_SB_CA<1>";
170"M_L_CPU0_SA_CA<1>";
171"M_L_CPU0_SB_CA<0>";
172"M_L_CPU0_SA_CA<0>";
173"M_L_CPU0_SB_CB<7>";
174"M_L_CPU0_SA_CB<1>";
175"M_L_CPU0_SA_CB<4>";
176"M_L_CPU0_SA_CB<7>";
177"GND\g";
178"PD_CHL_CPU0_DIMM_SAA";
%"TAP"
"1","(-6025,3925)","0","mstr_standard","I100";
;
CDS_LIB"mstr_standard"
BODY_TYPE"PLUMBING"
HDL_TAP"TRUE";
"B \NAC \NWC"5;
"S \NAC"
BN"8"120;
%"TAP"
"1","(-6025,3975)","0","mstr_standard","I101";
;
CDS_LIB"mstr_standard"
BODY_TYPE"PLUMBING"
HDL_TAP"TRUE";
"B \NAC \NWC"5;
"S \NAC"
BN"9"121;
%"TAP"
"1","(-6025,4025)","0","mstr_standard","I102";
;
CDS_LIB"mstr_standard"
BODY_TYPE"PLUMBING"
HDL_TAP"TRUE";
"B \NAC \NWC"5;
"S \NAC"
BN"10"122;
%"TAP"
"1","(-6025,4125)","0","mstr_standard","I103";
;
CDS_LIB"mstr_standard"
BODY_TYPE"PLUMBING"
HDL_TAP"TRUE";
"B \NAC \NWC"5;
"S \NAC"
BN"12"124;
%"TAP"
"1","(-6025,4075)","0","mstr_standard","I104";
;
CDS_LIB"mstr_standard"
BODY_TYPE"PLUMBING"
HDL_TAP"TRUE";
"B \NAC \NWC"5;
"S \NAC"
BN"11"123;
%"TAP"
"1","(-6025,4175)","0","mstr_standard","I105";
;
CDS_LIB"mstr_standard"
BODY_TYPE"PLUMBING"
HDL_TAP"TRUE";
"B \NAC \NWC"5;
"S \NAC"
BN"13"125;
%"TAP"
"1","(-6025,4225)","0","mstr_standard","I106";
;
CDS_LIB"mstr_standard"
BODY_TYPE"PLUMBING"
HDL_TAP"TRUE";
"B \NAC \NWC"5;
"S \NAC"
BN"14"126;
%"TAP"
"1","(-6025,4275)","0","mstr_standard","I107";
;
CDS_LIB"mstr_standard"
BODY_TYPE"PLUMBING"
HDL_TAP"TRUE";
"B \NAC \NWC"5;
"S \NAC"
BN"15"127;
%"TAP"
"1","(-6025,4325)","0","mstr_standard","I108";
;
CDS_LIB"mstr_standard"
BODY_TYPE"PLUMBING"
HDL_TAP"TRUE";
"B \NAC \NWC"5;
"S \NAC"
BN"16"128;
%"TAP"
"1","(-6025,4425)","0","mstr_standard","I109";
;
CDS_LIB"mstr_standard"
BODY_TYPE"PLUMBING"
HDL_TAP"TRUE";
"B \NAC \NWC"5;
"S \NAC"
BN"18"74;
%"TAP"
"1","(-6025,4375)","0","mstr_standard","I110";
;
CDS_LIB"mstr_standard"
BODY_TYPE"PLUMBING"
HDL_TAP"TRUE";
"B \NAC \NWC"5;
"S \NAC"
BN"17"129;
%"TAP"
"1","(-6025,4475)","0","mstr_standard","I111";
;
CDS_LIB"mstr_standard"
BODY_TYPE"PLUMBING"
HDL_TAP"TRUE";
"B \NAC \NWC"5;
"S \NAC"
BN"19"130;
%"TAP"
"1","(-6025,4525)","0","mstr_standard","I112";
;
CDS_LIB"mstr_standard"
BODY_TYPE"PLUMBING"
HDL_TAP"TRUE";
"B \NAC \NWC"5;
"S \NAC"
BN"20"131;
%"TAP"
"1","(-6025,4575)","0","mstr_standard","I113";
;
CDS_LIB"mstr_standard"
BODY_TYPE"PLUMBING"
HDL_TAP"TRUE";
"B \NAC \NWC"5;
"S \NAC"
BN"21"132;
%"TAP"
"1","(-6025,4625)","0","mstr_standard","I114";
;
CDS_LIB"mstr_standard"
BODY_TYPE"PLUMBING"
HDL_TAP"TRUE";
"B \NAC \NWC"5;
"S \NAC"
BN"22"133;
%"TAP"
"1","(-6025,4675)","0","mstr_standard","I115";
;
CDS_LIB"mstr_standard"
BODY_TYPE"PLUMBING"
HDL_TAP"TRUE";
"B \NAC \NWC"5;
"S \NAC"
BN"23"134;
%"TAP"
"1","(-6025,4725)","0","mstr_standard","I116";
;
CDS_LIB"mstr_standard"
BODY_TYPE"PLUMBING"
HDL_TAP"TRUE";
"B \NAC \NWC"5;
"S \NAC"
BN"24"135;
%"TAP"
"1","(-6025,4775)","0","mstr_standard","I117";
;
CDS_LIB"mstr_standard"
BODY_TYPE"PLUMBING"
HDL_TAP"TRUE";
"B \NAC \NWC"5;
"S \NAC"
BN"25"136;
%"TAP"
"1","(-6025,4825)","0","mstr_standard","I118";
;
CDS_LIB"mstr_standard"
BODY_TYPE"PLUMBING"
HDL_TAP"TRUE";
"B \NAC \NWC"5;
"S \NAC"
BN"26"137;
%"TAP"
"1","(-6025,4875)","0","mstr_standard","I119";
;
CDS_LIB"mstr_standard"
BODY_TYPE"PLUMBING"
HDL_TAP"TRUE";
"B \NAC \NWC"5;
"S \NAC"
BN"27"138;
%"TAP"
"1","(-6025,4925)","0","mstr_standard","I120";
;
CDS_LIB"mstr_standard"
BODY_TYPE"PLUMBING"
HDL_TAP"TRUE";
"B \NAC \NWC"5;
"S \NAC"
BN"28"139;
%"TAP"
"1","(-6025,5025)","0","mstr_standard","I121";
;
CDS_LIB"mstr_standard"
BODY_TYPE"PLUMBING"
HDL_TAP"TRUE";
"B \NAC \NWC"5;
"S \NAC"
BN"30"75;
%"TAP"
"1","(-6025,5075)","0","mstr_standard","I122";
;
CDS_LIB"mstr_standard"
BODY_TYPE"PLUMBING"
HDL_TAP"TRUE";
"B \NAC \NWC"5;
"S \NAC"
BN"31"76;
%"TAP"
"1","(-6025,4975)","0","mstr_standard","I123";
;
CDS_LIB"mstr_standard"
BODY_TYPE"PLUMBING"
HDL_TAP"TRUE";
"B \NAC \NWC"5;
"S \NAC"
BN"29"140;
%"GND"
"1","(-6450,700)","0","mstr_symbols","I126";
;
BOM_COST"MEM"
SIZE"1B"
CDS_LIB"mstr_symbols"
BODY_TYPE"PLUMBING"
VOLTAGE"0.0"
HDL_POWER"GND";
"A\NAC"11;
%"Q_RES"
"2","(-6450,925)","0","pure_quanta","I127";
;
LOCATION"R769"
$SEC"1"
CDS_SEC"1"
WATTAGE"1/16W"
MATERIAL"CHIP"
TOLERANCE"1%"
VALUE"84.5K"
PART_NUMBER"CS38452FB05"
PACK_TYPE"0402LF"
CDS_LIB"pure_quanta";
"A"
$PN"1"178;
"B"
$PN"2"11;
%"GND"
"1","(-2200,1750)","0","mstr_symbols","I138";
;
CDS_LIB"mstr_symbols"
SIZE"1B"
BODY_TYPE"PLUMBING"
VOLTAGE"0.0"
HDL_POWER"GND";
"A\NAC"31;
%"GND"
"1","(-400,1525)","0","mstr_symbols","I139";
;
CDS_LIB"mstr_symbols"
SIZE"1B"
BODY_TYPE"PLUMBING"
VOLTAGE"0.0"
HDL_POWER"GND";
"A\NAC"33;
%"SCONN288_DDR506112002KQ"
"3","(-1300,3525)","0","pure_quanta","I140";
;
LOCATION"J67"
$SEC"3"
CDS_SEC"3"
VALUE"SCONN288_DDR506112002KQ"
PART_TYPE"SMLF"
MATERIAL"IO"
PART_NUMBER"DFHST8FS479"
CDS_LMAN_SYM_OUTLINE"-450,1800,450,-1750"
NEEDS_NO_SIZE"TRUE"
CDS_LIB"pure_quanta";
"G3"
$PN"G3"33;
"G2"
$PN"G2"33;
"G1"
$PN"G1"33;
"VSS62"
$PN"141"33;
"VSS61"
$PN"139"33;
"VSS60"
$PN"136"33;
"VSS58"
$PN"132"33;
"VSS104"
$PN"240"31;
"VSS102"
$PN"235"31;
"VSS100"
$PN"230"31;
"VIN_BULK2"
$PN"146"32;
"VIN_BULK1"
$PN"145"32;
"VIN_BULK0"
$PN"1"32;
"VSS126"
$PN"288"31;
"VSS125"
$PN"286"31;
"VSS124"
$PN"284"31;
"VSS123"
$PN"281"31;
"VSS122"
$PN"279"31;
"VSS121"
$PN"277"31;
"VSS120"
$PN"275"31;
"VSS119"
$PN"273"31;
"VSS118"
$PN"270"31;
"VSS117"
$PN"268"31;
"VSS116"
$PN"266"31;
"VSS115"
$PN"264"31;
"VSS114"
$PN"262"31;
"VSS113"
$PN"259"31;
"VSS112"
$PN"257"31;
"VSS111"
$PN"255"31;
"VSS110"
$PN"253"31;
"VSS109"
$PN"251"31;
"VSS108"
$PN"248"31;
"VSS107"
$PN"246"31;
"VSS106"
$PN"244"31;
"VSS105"
$PN"242"31;
"VSS103"
$PN"237"31;
"VSS101"
$PN"233"31;
"VSS99"
$PN"228"31;
"VSS98"
$PN"226"31;
"VSS97"
$PN"224"31;
"VSS96"
$PN"222"31;
"VSS95"
$PN"219"31;
"VSS94"
$PN"216"31;
"VSS93"
$PN"214"31;
"VSS92"
$PN"212"31;
"VSS91"
$PN"210"31;
"VSS90"
$PN"208"31;
"VSS89"
$PN"206"31;
"VSS88"
$PN"204"31;
"VSS87"
$PN"202"31;
"VSS86"
$PN"199"31;
"VSS85"
$PN"197"31;
"VSS84"
$PN"195"31;
"VSS83"
$PN"193"31;
"VSS82"
$PN"191"31;
"VSS81"
$PN"188"31;
"VSS80"
$PN"186"31;
"VSS79"
$PN"184"31;
"VSS78"
$PN"182"31;
"VSS77"
$PN"180"31;
"VSS76"
$PN"177"31;
"VSS75"
$PN"175"31;
"VSS74"
$PN"173"31;
"VSS73"
$PN"171"31;
"VSS72"
$PN"169"31;
"VSS71"
$PN"166"31;
"VSS70"
$PN"164"31;
"VSS69"
$PN"162"31;
"VSS68"
$PN"160"31;
"VSS67"
$PN"158"31;
"VSS66"
$PN"155"31;
"VSS65"
$PN"153"31;
"VSS64"
$PN"151"31;
"VSS63"
$PN"143"33;
"VSS59"
$PN"134"33;
"VSS57"
$PN"130"33;
"VSS56"
$PN"128"33;
"VSS55"
$PN"125"33;
"VSS54"
$PN"123"33;
"VSS53"
$PN"121"33;
"VSS52"
$PN"119"33;
"VSS51"
$PN"117"33;
"VSS50"
$PN"114"33;
"VSS49"
$PN"112"33;
"VSS48"
$PN"110"33;
"VSS47"
$PN"108"33;
"VSS46"
$PN"106"33;
"VSS45"
$PN"103"33;
"VSS44"
$PN"101"33;
"VSS43"
$PN"99"33;
"VSS42"
$PN"97"33;
"VSS41"
$PN"95"33;
"VSS40"
$PN"92"33;
"VSS39"
$PN"90"33;
"VSS38"
$PN"88"33;
"VSS37"
$PN"85"33;
"VSS36"
$PN"83"33;
"VSS35"
$PN"81"33;
"VSS34"
$PN"79"33;
"VSS33"
$PN"77"33;
"VSS32"
$PN"75"33;
"VSS31"
$PN"73"33;
"VSS30"
$PN"71"33;
"VSS29"
$PN"69"33;
"VSS28"
$PN"67"33;
"VSS27"
$PN"65"33;
"VSS26"
$PN"63"33;
"VSS25"
$PN"61"33;
"VSS24"
$PN"59"33;
"VSS23"
$PN"57"33;
"VSS22"
$PN"54"33;
"VSS21"
$PN"52"33;
"VSS20"
$PN"50"33;
"VSS19"
$PN"48"33;
"VSS18"
$PN"46"33;
"VSS17"
$PN"43"33;
"VSS16"
$PN"41"33;
"VSS15"
$PN"39"33;
"VSS14"
$PN"37"33;
"VSS13"
$PN"35"33;
"VSS12"
$PN"32"33;
"VSS11"
$PN"30"33;
"VSS10"
$PN"28"33;
"VSS9"
$PN"26"33;
"VSS8"
$PN"24"33;
"VSS7"
$PN"21"33;
"VSS6"
$PN"19"33;
"VSS5"
$PN"17"33;
"VSS4"
$PN"15"33;
"VSS3"
$PN"13"33;
"VSS2"
$PN"10"33;
"VSS1"
$PN"8"33;
"VSS0"
$PN"6"33;
%"Q_CAP"
"1","(-8600,2900)","2","pure_quanta","I185";
;
LOCATION"C132"
$SEC"1"
CDS_SEC"1"
MATERIAL"X7R"
TOLERANCE"10%"
VALUE"0.1UF"
VOLTAGE"25V"
PACK_TYPE"0402"
PART_NUMBER"CH4104K1B00"
CDS_LIB"pure_quanta"
BOM_COST"MEM"
ROOM"MEM_CH_A_CPU0_DIMM1";
"B"
$PN"2"12;
"A"
$PN"1"18;
%"GND"
"1","(-8600,2675)","0","mstr_symbols","I186";
;
CDS_LIB"mstr_symbols"
SIZE"1B"
BOM_COST"MEM"
BODY_TYPE"PLUMBING"
VOLTAGE"0"
ROOM"MEM_EFGH_DECOUPLING_CAPS"
HDL_POWER"GND";
"A\NAC"12;
%"Q_RES"
"1","(-8475,1825)","2","pure_quanta","I188";
;
LOCATION"R302"
$SEC"1"
CDS_SEC"1"
VALUE"0"
CDS_LIB"pure_quanta"
BOM_COST"MEM"
WATTAGE"1/16W"
MATERIAL"CHIP"
TOLERANCE"5%"
PART_NUMBER"CS00002JB38"
PACK_TYPE"0402LF"
ROOM"RST_CPU0_PLD_TO_DIMM";
"B"
$PN"2"30;
"A"
$PN"1"19;
%"Q_RES"
"2","(-8350,1975)","0","pure_quanta","I189";
;
LOCATION"R101"
$SEC"1"
CDS_SEC"1"
WATTAGE"1/16W"
MATERIAL"EMPTY"
TOLERANCE"5%"
VALUE"1K"
PACK_TYPE"0402LF"
CDS_LIB"pure_quanta"
BOM_COST"MEM"
PART_NUMBER"TMP_QCS21002JB34"
ROOM"MEM_CH_A_CPU0_DIMM1";
"A"
$PN"1"13;
"B"
$PN"2"19;
%"VCC_CORE"
"1","(-8350,2150)","0","mstr_symbols","I190";
;
HDL_POWER"P3V3_STBY"
CDS_LIB"mstr_symbols"
VOLTAGE"3.3"
ROOM"PVCCINFAON_CPU0_CTRL";
"A"13;
%"TAP"
"1","(-3300,4250)","0","mstr_standard","I194";
;
CDS_LIB"mstr_standard"
BODY_TYPE"PLUMBING"
HDL_TAP"TRUE";
"B \NAC \NWC"7;
"S \NAC"
BN"9"37;
%"TAP"
"1","(-3500,4200)","0","mstr_standard","I195";
;
CDS_LIB"mstr_standard"
BODY_TYPE"PLUMBING"
HDL_TAP"TRUE";
"B \NAC \NWC"8;
"S \NAC"
BN"8"38;
%"TAP"
"1","(-3500,4300)","0","mstr_standard","I196";
;
CDS_LIB"mstr_standard"
BODY_TYPE"PLUMBING"
HDL_TAP"TRUE";
"B \NAC \NWC"8;
"S \NAC"
BN"9"36;
%"TAP"
"1","(-3300,4150)","0","mstr_standard","I197";
;
CDS_LIB"mstr_standard"
BODY_TYPE"PLUMBING"
HDL_TAP"TRUE";
"B \NAC \NWC"7;
"S \NAC"
BN"8"39;
%"TAP"
"1","(-3300,4050)","0","mstr_standard","I198";
;
CDS_LIB"mstr_standard"
BODY_TYPE"PLUMBING"
HDL_TAP"TRUE";
"B \NAC \NWC"7;
"S \NAC"
BN"7"73;
%"TAP"
"1","(-3300,3950)","0","mstr_standard","I199";
;
CDS_LIB"mstr_standard"
BODY_TYPE"PLUMBING"
HDL_TAP"TRUE";
"B \NAC \NWC"7;
"S \NAC"
BN"6"44;
%"TAP"
"1","(-3500,4100)","0","mstr_standard","I200";
;
CDS_LIB"mstr_standard"
BODY_TYPE"PLUMBING"
HDL_TAP"TRUE";
"B \NAC \NWC"8;
"S \NAC"
BN"7"41;
%"TAP"
"1","(-3500,4000)","0","mstr_standard","I201";
;
CDS_LIB"mstr_standard"
BODY_TYPE"PLUMBING"
HDL_TAP"TRUE";
"B \NAC \NWC"8;
"S \NAC"
BN"6"72;
%"TAP"
"1","(-3300,3750)","0","mstr_standard","I202";
;
CDS_LIB"mstr_standard"
BODY_TYPE"PLUMBING"
HDL_TAP"TRUE";
"B \NAC \NWC"7;
"S \NAC"
BN"4"52;
%"TAP"
"1","(-3300,3850)","0","mstr_standard","I203";
;
CDS_LIB"mstr_standard"
BODY_TYPE"PLUMBING"
HDL_TAP"TRUE";
"B \NAC \NWC"7;
"S \NAC"
BN"5"48;
%"TAP"
"1","(-3500,3900)","0","mstr_standard","I204";
;
CDS_LIB"mstr_standard"
BODY_TYPE"PLUMBING"
HDL_TAP"TRUE";
"B \NAC \NWC"8;
"S \NAC"
BN"5"47;
%"TAP"
"1","(-3500,3700)","0","mstr_standard","I205";
;
CDS_LIB"mstr_standard"
BODY_TYPE"PLUMBING"
HDL_TAP"TRUE";
"B \NAC \NWC"8;
"S \NAC"
BN"3"55;
%"TAP"
"1","(-3500,3800)","0","mstr_standard","I206";
;
CDS_LIB"mstr_standard"
BODY_TYPE"PLUMBING"
HDL_TAP"TRUE";
"B \NAC \NWC"8;
"S \NAC"
BN"4"51;
%"TAP"
"1","(-3300,3550)","0","mstr_standard","I207";
;
CDS_LIB"mstr_standard"
BODY_TYPE"PLUMBING"
HDL_TAP"TRUE";
"B \NAC \NWC"7;
"S \NAC"
BN"2"60;
%"TAP"
"1","(-3300,3650)","0","mstr_standard","I208";
;
CDS_LIB"mstr_standard"
BODY_TYPE"PLUMBING"
HDL_TAP"TRUE";
"B \NAC \NWC"7;
"S \NAC"
BN"3"56;
%"TAP"
"1","(-3300,3450)","0","mstr_standard","I209";
;
CDS_LIB"mstr_standard"
BODY_TYPE"PLUMBING"
HDL_TAP"TRUE";
"B \NAC \NWC"7;
"S \NAC"
BN"1"64;
%"TAP"
"1","(-3500,3600)","0","mstr_standard","I210";
;
CDS_LIB"mstr_standard"
BODY_TYPE"PLUMBING"
HDL_TAP"TRUE";
"B \NAC \NWC"8;
"S \NAC"
BN"2"59;
%"TAP"
"1","(-3500,3500)","0","mstr_standard","I211";
;
CDS_LIB"mstr_standard"
BODY_TYPE"PLUMBING"
HDL_TAP"TRUE";
"B \NAC \NWC"8;
"S \NAC"
BN"1"63;
%"TAP"
"1","(-3300,3200)","0","mstr_standard","I214";
;
CDS_LIB"mstr_standard"
BODY_TYPE"PLUMBING"
HDL_TAP"TRUE";
"B \NAC \NWC"9;
"S \NAC"
BN"9"35;
%"TAP"
"1","(-3300,3350)","0","mstr_standard","I215";
;
CDS_LIB"mstr_standard"
BODY_TYPE"PLUMBING"
HDL_TAP"TRUE";
"B \NAC \NWC"7;
"S \NAC"
BN"0"68;
%"TAP"
"1","(-3500,3400)","0","mstr_standard","I216";
;
CDS_LIB"mstr_standard"
BODY_TYPE"PLUMBING"
HDL_TAP"TRUE";
"B \NAC \NWC"8;
"S \NAC"
BN"0"67;
%"TAP"
"1","(-3500,3250)","0","mstr_standard","I217";
;
CDS_LIB"mstr_standard"
BODY_TYPE"PLUMBING"
HDL_TAP"TRUE";
"B \NAC \NWC"10;
"S \NAC"
BN"9"34;
%"TAP"
"1","(-3300,3100)","0","mstr_standard","I218";
;
CDS_LIB"mstr_standard"
BODY_TYPE"PLUMBING"
HDL_TAP"TRUE";
"B \NAC \NWC"9;
"S \NAC"
BN"8"70;
%"TAP"
"1","(-3300,3000)","0","mstr_standard","I219";
;
CDS_LIB"mstr_standard"
BODY_TYPE"PLUMBING"
HDL_TAP"TRUE";
"B \NAC \NWC"9;
"S \NAC"
BN"7"40;
%"SCONN288_DDR506112002KQ"
"1","(-6875,3325)","0","pure_quanta","I22";
;
LOCATION"J67"
$SEC"1"
CDS_SEC"1"
PART_TYPE"SMLF"
VALUE"SCONN288_DDR506112002KQ"
MATERIAL"IO"
PART_NUMBER"DFHST8FS479"
CDS_LMAN_SYM_OUTLINE"-450,1900,450,-1850"
NEEDS_NO_SIZE"TRUE"
CDS_LIB"pure_quanta";
"PWR_GOOD||FAIL_N"
$PN"147"19;
"DQ31_A"
$PN"194"76;
"CB7_A"
$PN"205"176;
"CB4_A"
$PN"58"175;
"CB1_A"
$PN"53"174;
"CB7_B"
$PN"236"173;
"ALERT_N \B"
$PN"62"21;
"CA0_A"
$PN"66"172;
"CA0_B"
$PN"76"171;
"CA1_A"
$PN"211"170;
"CA1_B"
$PN"221"169;
"CA2_A"
$PN"68"168;
"CA2_B"
$PN"78"167;
"CA3_A"
$PN"213"166;
"CA3_B"
$PN"223"165;
"CA4_A"
$PN"70"164;
"CA4_B"
$PN"80"163;
"CA5_A"
$PN"215"162;
"CA5_B"
$PN"225"161;
"CA6_A"
$PN"72"160;
"CA6_B"
$PN"82"159;
"CB6_A"
$PN"203"158;
"CB5_A"
$PN"60"157;
"CB3_A"
$PN"198"156;
"CB2_A"
$PN"196"155;
"CB0_A"
$PN"51"154;
"CB6_B"
$PN"234"153;
"CB5_B"
$PN"91"152;
"CB4_B"
$PN"89"151;
"CB3_B"
$PN"243"150;
"CB2_B"
$PN"241"149;
"CB1_B"
$PN"98"148;
"CB0_B"
$PN"96"147;
"CK_C \B"
$PN"218"146;
"CK_T"
$PN"217"145;
"CS0_A_N"
$PN"64"144;
"CS0_B_N"
$PN"84"143;
"CS1_A_N"
$PN"209"142;
"CS1_B_N"
$PN"229"141;
"DQ30_A"
$PN"192"75;
"DQ29_A"
$PN"49"140;
"DQ28_A"
$PN"47"139;
"DQ27_A"
$PN"187"138;
"DQ26_A"
$PN"185"137;
"DQ25_A"
$PN"42"136;
"DQ24_A"
$PN"40"135;
"DQ23_A"
$PN"183"134;
"DQ22_A"
$PN"181"133;
"DQ21_A"
$PN"38"132;
"DQ20_A"
$PN"36"131;
"DQ19_A"
$PN"176"130;
"DQ18_A"
$PN"174"74;
"DQ17_A"
$PN"31"129;
"DQ16_A"
$PN"29"128;
"DQ15_A"
$PN"172"127;
"DQ14_A"
$PN"170"126;
"DQ13_A"
$PN"27"125;
"DQ12_A"
$PN"25"124;
"DQ11_A"
$PN"165"123;
"DQ10_A"
$PN"163"122;
"DQ9_A"
$PN"20"121;
"DQ8_A"
$PN"18"120;
"DQ7_A"
$PN"161"119;
"DQ6_A"
$PN"159"118;
"DQ5_A"
$PN"16"117;
"DQ4_A"
$PN"14"116;
"DQ3_A"
$PN"154"115;
"DQ2_A"
$PN"152"114;
"DQ1_A"
$PN"9"113;
"DQ0_A"
$PN"7"112;
"DQ31_B"
$PN"287"111;
"DQ30_B"
$PN"285"110;
"DQ29_B"
$PN"142"109;
"DQ28_B"
$PN"140"108;
"DQ27_B"
$PN"280"107;
"DQ26_B"
$PN"278"106;
"DQ25_B"
$PN"135"105;
"DQ24_B"
$PN"133"104;
"DQ23_B"
$PN"276"103;
"DQ22_B"
$PN"274"102;
"DQ21_B"
$PN"131"101;
"DQ20_B"
$PN"129"100;
"DQ19_B"
$PN"269"99;
"DQ18_B"
$PN"267"98;
"DQ17_B"
$PN"124"97;
"DQ16_B"
$PN"122"96;
"DQ15_B"
$PN"265"95;
"DQ14_B"
$PN"263"94;
"DQ13_B"
$PN"120"93;
"DQ12_B"
$PN"118"92;
"DQ11_B"
$PN"258"91;
"DQ10_B"
$PN"256"90;
"DQ9_B"
$PN"113"89;
"DQ8_B"
$PN"111"88;
"DQ7_B"
$PN"254"87;
"DQ6_B"
$PN"252"86;
"DQ5_B"
$PN"109"85;
"DQ4_B"
$PN"107"84;
"DQ3_B"
$PN"247"83;
"DQ2_B"
$PN"245"82;
"DQ1_B"
$PN"102"81;
"DQ0_B"
$PN"100"80;
"HAS"
$PN"148"17;
"HSCL"
$PN"4"15;
"HSDA"
$PN"5"16;
"LBD||RSP_A_N"
$PN"86"29;
"LBS||RSP_B_N"
$PN"87"23;
"PAR_A"
$PN"74"79;
"PAR_B"
$PN"227"78;
"RESET_N \B"
$PN"207"22;
"RFU6"
$PN"232"20;
"RFU5"
$PN"231"77;
"RFU4"
$PN"220"26;
"RFU3"
$PN"150"27;
"RFU2"
$PN"149"28;
"RFU1"
$PN"144"24;
"RFU0"
$PN"2"25;
"VIN_MGMT"
$PN"3"18;
%"TAP"
"1","(-3500,3150)","0","mstr_standard","I220";
;
CDS_LIB"mstr_standard"
BODY_TYPE"PLUMBING"
HDL_TAP"TRUE";
"B \NAC \NWC"10;
"S \NAC"
BN"8"71;
%"TAP"
"1","(-3500,3050)","0","mstr_standard","I221";
;
CDS_LIB"mstr_standard"
BODY_TYPE"PLUMBING"
HDL_TAP"TRUE";
"B \NAC \NWC"10;
"S \NAC"
BN"7"69;
%"TAP"
"1","(-3500,2950)","0","mstr_standard","I222";
;
CDS_LIB"mstr_standard"
BODY_TYPE"PLUMBING"
HDL_TAP"TRUE";
"B \NAC \NWC"10;
"S \NAC"
BN"6"42;
%"TAP"
"1","(-3300,2800)","0","mstr_standard","I223";
;
CDS_LIB"mstr_standard"
BODY_TYPE"PLUMBING"
HDL_TAP"TRUE";
"B \NAC \NWC"9;
"S \NAC"
BN"5"46;
%"TAP"
"1","(-3300,2900)","0","mstr_standard","I224";
;
CDS_LIB"mstr_standard"
BODY_TYPE"PLUMBING"
HDL_TAP"TRUE";
"B \NAC \NWC"9;
"S \NAC"
BN"6"43;
%"TAP"
"1","(-3300,2700)","0","mstr_standard","I225";
;
CDS_LIB"mstr_standard"
BODY_TYPE"PLUMBING"
HDL_TAP"TRUE";
"B \NAC \NWC"9;
"S \NAC"
BN"4"50;
%"TAP"
"1","(-3500,2850)","0","mstr_standard","I226";
;
CDS_LIB"mstr_standard"
BODY_TYPE"PLUMBING"
HDL_TAP"TRUE";
"B \NAC \NWC"10;
"S \NAC"
BN"5"45;
%"TAP"
"1","(-3500,2750)","0","mstr_standard","I227";
;
CDS_LIB"mstr_standard"
BODY_TYPE"PLUMBING"
HDL_TAP"TRUE";
"B \NAC \NWC"10;
"S \NAC"
BN"4"49;
%"TAP"
"1","(-3300,2500)","0","mstr_standard","I228";
;
CDS_LIB"mstr_standard"
BODY_TYPE"PLUMBING"
HDL_TAP"TRUE";
"B \NAC \NWC"9;
"S \NAC"
BN"2"58;
%"TAP"
"1","(-3300,2600)","0","mstr_standard","I229";
;
CDS_LIB"mstr_standard"
BODY_TYPE"PLUMBING"
HDL_TAP"TRUE";
"B \NAC \NWC"9;
"S \NAC"
BN"3"54;
%"TAP"
"1","(-7725,2875)","2","mstr_standard","I23";
;
CDS_LIB"mstr_standard"
BODY_TYPE"PLUMBING"
HDL_TAP"TRUE";
"B \NAC \NWC"4;
"S \NAC"
BN"0"147;
%"TAP"
"1","(-3300,2400)","0","mstr_standard","I230";
;
CDS_LIB"mstr_standard"
BODY_TYPE"PLUMBING"
HDL_TAP"TRUE";
"B \NAC \NWC"9;
"S \NAC"
BN"1"62;
%"TAP"
"1","(-3500,2650)","0","mstr_standard","I231";
;
CDS_LIB"mstr_standard"
BODY_TYPE"PLUMBING"
HDL_TAP"TRUE";
"B \NAC \NWC"10;
"S \NAC"
BN"3"53;
%"TAP"
"1","(-3500,2550)","0","mstr_standard","I232";
;
CDS_LIB"mstr_standard"
BODY_TYPE"PLUMBING"
HDL_TAP"TRUE";
"B \NAC \NWC"10;
"S \NAC"
BN"2"57;
%"TAP"
"1","(-3500,2450)","0","mstr_standard","I233";
;
CDS_LIB"mstr_standard"
BODY_TYPE"PLUMBING"
HDL_TAP"TRUE";
"B \NAC \NWC"10;
"S \NAC"
BN"1"61;
%"TAP"
"1","(-3300,2300)","0","mstr_standard","I234";
;
CDS_LIB"mstr_standard"
BODY_TYPE"PLUMBING"
HDL_TAP"TRUE";
"B \NAC \NWC"9;
"S \NAC"
BN"0"66;
%"TAP"
"1","(-3500,2350)","0","mstr_standard","I235";
;
CDS_LIB"mstr_standard"
BODY_TYPE"PLUMBING"
HDL_TAP"TRUE";
"B \NAC \NWC"10;
"S \NAC"
BN"0"65;
%"SCONN288_DDR506112002KQ"
"2","(-4450,3300)","0","pure_quanta","I236";
;
LOCATION"J67"
$SEC"2"
CDS_SEC"2"
PART_TYPE"SMLF"
VALUE"SCONN288_DDR506112002KQ"
MATERIAL"IO"
PART_NUMBER"DFHST8FS479"
CDS_LMAN_SYM_OUTLINE"-600,1150,600,-1150"
NEEDS_NO_SIZE"TRUE"
CDS_LIB"pure_quanta";
"DQS7_A_C||TDQS7_A_C \B"
$PN"178"73;
"DQS6_A_T||TDQS6_A_T"
$PN"168"72;
"DQS8_B_T||TDQS8_B_T"
$PN"283"71;
"DQS8_B_C||TDQS8_B_C \B"
$PN"282"70;
"DQS7_B_T||TDQS7_B_T"
$PN"272"69;
"DQS0_A_C \B"
$PN"12"68;
"DQS0_A_T"
$PN"11"67;
"DQS0_B_C \B"
$PN"105"66;
"DQS0_B_T"
$PN"104"65;
"DQS1_A_C \B"
$PN"23"64;
"DQS1_A_T"
$PN"22"63;
"DQS1_B_C \B"
$PN"116"62;
"DQS1_B_T"
$PN"115"61;
"DQS2_A_C \B"
$PN"34"60;
"DQS2_A_T"
$PN"33"59;
"DQS2_B_C \B"
$PN"127"58;
"DQS2_B_T"
$PN"126"57;
"DQS3_A_C \B"
$PN"45"56;
"DQS3_A_T"
$PN"44"55;
"DQS3_B_C \B"
$PN"138"54;
"DQS3_B_T"
$PN"137"53;
"DQS4_A_C \B"
$PN"56"52;
"DQS4_A_T"
$PN"55"51;
"DQS4_B_C \B"
$PN"238"50;
"DQS4_B_T"
$PN"239"49;
"DQS5_A_C||TDQS5_A_C||DQS5_A_T||TDQS5_A_T \B"
$PN"156"48;
"DQS5_A_T||TDQS5_A_T"
$PN"157"47;
"DQS5_B_C||TDQS5_B_C \B"
$PN"249"46;
"DQS5_B_T||TDQS5_B_T"
$PN"250"45;
"DQS6_A_C||TDQS6_A_C||DQS6_A_T||TDQS6_A_T \B"
$PN"167"44;
"DQS6_B_C||TDQS6_B_C \B"
$PN"260"43;
"DQS6_B_T||TDQS6_B_T"
$PN"261"42;
"DQS7_A_T||TDQS7_A_T"
$PN"179"41;
"DQS7_B_C||TDQS7_B_C \B"
$PN"271"40;
"DQS8_A_C||TDQS8_A_C \B"
$PN"189"39;
"DQS8_A_T||TDQS8_A_T"
$PN"190"38;
"DQS9_A_C||TDQS9_A_C \B"
$PN"200"37;
"DQS9_A_T||TDQS9_A_T"
$PN"201"36;
"DQS9_B_C||TDQS9_B_C \B"
$PN"94"35;
"DQS9_B_T||TDQS9_B_T||DBI4_B_N"
$PN"93"34;
%"GND"
"1","(-2900,5250)","0","pure_quanta_power","I237";
;
SIZE"1B"
BOM_COST"MEM"
CDS_LIB"pure_quanta_power"
ROOM"MEM_EFGH_DECOUPLING_CAPS"
HDL_POWER"GND";
"A<SIZE-1..0>\NAC"177;
%"Q_CAP"
"1","(-2900,5600)","2","pure_quanta","I238";
;
LOCATION"C170"
$SEC"1"
CDS_SEC"1"
VALUE"10UF"
PART_NUMBER"CH6104KEA00"
VOLTAGE"25V"
PACK_TYPE"C0805"
MATERIAL"X6S"
TOLERANCE"10%"
CDS_LIB"pure_quanta"
BOM_COST"MEM"
ROOM"MEM_CH_A_CPU0_DIMM1";
"B"
$PN"2"177;
"A"
$PN"1"32;
%"Q_CAP"
"1","(-2325,5600)","2","pure_quanta","I239";
;
LOCATION"C171"
$SEC"1"
CDS_SEC"1"
TOLERANCE"10%"
VALUE"10UF"
VOLTAGE"25V"
PACK_TYPE"C0805"
MATERIAL"X6S"
PART_NUMBER"CH6104KEA00"
CDS_LIB"pure_quanta"
BOM_COST"MEM"
ROOM"MEM_CH_A_CPU0_DIMM1";
"B"
$PN"2"177;
"A"
$PN"1"32;
%"TAP"
"1","(-7725,2925)","2","mstr_standard","I24";
;
CDS_LIB"mstr_standard"
BODY_TYPE"PLUMBING"
HDL_TAP"TRUE";
"B \NAC \NWC"4;
"S \NAC"
BN"1"148;
%"UNIVERSAL_POWER"
"1","(-2900,5925)","0","pure_quanta_power","I240";
;
HDL_POWER"P12V_MEM_0"
CDS_LIB"pure_quanta_power"
BOM_COST"VR_SYSTEM";
"A"32;
%"Q_RES"
"1","(-7775,2375)","0","pure_quanta","I242";
;
$LOCATION"R1579"
CDS_LOCATION"R1579"
$SEC"1"
CDS_SEC"1"
VALUE"49.9"
PART_NUMBER"CS04992FB07"
TOLERANCE"1%"
WATTAGE"1/16W"
PACK_TYPE"0402LF"
MATERIAL"CHIP"
CDS_LIB"pure_quanta";
"B"
$PN"2"15;
"A"
$PN"1"14;
%"TAP"
"1","(-7725,2975)","2","mstr_standard","I25";
;
CDS_LIB"mstr_standard"
BODY_TYPE"PLUMBING"
HDL_TAP"TRUE";
"B \NAC \NWC"4;
"S \NAC"
BN"2"149;
%"TAP"
"1","(-7725,3075)","2","mstr_standard","I26";
;
CDS_LIB"mstr_standard"
BODY_TYPE"PLUMBING"
HDL_TAP"TRUE";
"B \NAC \NWC"4;
"S \NAC"
BN"4"151;
%"TAP"
"1","(-7725,3125)","2","mstr_standard","I27";
;
CDS_LIB"mstr_standard"
BODY_TYPE"PLUMBING"
HDL_TAP"TRUE";
"B \NAC \NWC"4;
"S \NAC"
BN"5"152;
%"TAP"
"1","(-7725,3025)","2","mstr_standard","I28";
;
CDS_LIB"mstr_standard"
BODY_TYPE"PLUMBING"
HDL_TAP"TRUE";
"B \NAC \NWC"4;
"S \NAC"
BN"3"150;
%"TAP"
"1","(-7725,3225)","2","mstr_standard","I29";
;
CDS_LIB"mstr_standard"
BODY_TYPE"PLUMBING"
HDL_TAP"TRUE";
"B \NAC \NWC"4;
"S \NAC"
BN"7"173;
%"TAP"
"1","(-7725,3375)","2","mstr_standard","I30";
;
CDS_LIB"mstr_standard"
BODY_TYPE"PLUMBING"
HDL_TAP"TRUE";
"B \NAC \NWC"1;
"S \NAC"
BN"1"174;
%"TAP"
"1","(-7725,3325)","2","mstr_standard","I31";
;
CDS_LIB"mstr_standard"
BODY_TYPE"PLUMBING"
HDL_TAP"TRUE";
"B \NAC \NWC"1;
"S \NAC"
BN"0"154;
%"TAP"
"1","(-7725,3175)","2","mstr_standard","I32";
;
CDS_LIB"mstr_standard"
BODY_TYPE"PLUMBING"
HDL_TAP"TRUE";
"B \NAC \NWC"4;
"S \NAC"
BN"6"153;
%"TAP"
"1","(-6025,1875)","0","mstr_standard","I33";
;
CDS_LIB"mstr_standard"
BODY_TYPE"PLUMBING"
HDL_TAP"TRUE";
"B \NAC \NWC"6;
"S \NAC"
BN"0"80;
%"TAP"
"1","(-6025,1925)","0","mstr_standard","I34";
;
CDS_LIB"mstr_standard"
BODY_TYPE"PLUMBING"
HDL_TAP"TRUE";
"B \NAC \NWC"6;
"S \NAC"
BN"1"81;
%"TAP"
"1","(-6025,1975)","0","mstr_standard","I35";
;
CDS_LIB"mstr_standard"
BODY_TYPE"PLUMBING"
HDL_TAP"TRUE";
"B \NAC \NWC"6;
"S \NAC"
BN"2"82;
%"TAP"
"1","(-6025,2025)","0","mstr_standard","I36";
;
CDS_LIB"mstr_standard"
BODY_TYPE"PLUMBING"
HDL_TAP"TRUE";
"B \NAC \NWC"6;
"S \NAC"
BN"3"83;
%"TAP"
"1","(-6025,2075)","0","mstr_standard","I37";
;
CDS_LIB"mstr_standard"
BODY_TYPE"PLUMBING"
HDL_TAP"TRUE";
"B \NAC \NWC"6;
"S \NAC"
BN"4"84;
%"TAP"
"1","(-6025,2125)","0","mstr_standard","I38";
;
CDS_LIB"mstr_standard"
BODY_TYPE"PLUMBING"
HDL_TAP"TRUE";
"B \NAC \NWC"6;
"S \NAC"
BN"5"85;
%"TAP"
"1","(-6025,2175)","0","mstr_standard","I39";
;
CDS_LIB"mstr_standard"
BODY_TYPE"PLUMBING"
HDL_TAP"TRUE";
"B \NAC \NWC"6;
"S \NAC"
BN"6"86;
%"TAP"
"1","(-6025,2225)","0","mstr_standard","I40";
;
CDS_LIB"mstr_standard"
BODY_TYPE"PLUMBING"
HDL_TAP"TRUE";
"B \NAC \NWC"6;
"S \NAC"
BN"7"87;
%"TAP"
"1","(-6025,2275)","0","mstr_standard","I41";
;
CDS_LIB"mstr_standard"
BODY_TYPE"PLUMBING"
HDL_TAP"TRUE";
"B \NAC \NWC"6;
"S \NAC"
BN"8"88;
%"TAP"
"1","(-6025,2375)","0","mstr_standard","I42";
;
CDS_LIB"mstr_standard"
BODY_TYPE"PLUMBING"
HDL_TAP"TRUE";
"B \NAC \NWC"6;
"S \NAC"
BN"10"90;
%"TAP"
"1","(-6025,2325)","0","mstr_standard","I43";
;
CDS_LIB"mstr_standard"
BODY_TYPE"PLUMBING"
HDL_TAP"TRUE";
"B \NAC \NWC"6;
"S \NAC"
BN"9"89;
%"TAP"
"1","(-6025,2425)","0","mstr_standard","I44";
;
CDS_LIB"mstr_standard"
BODY_TYPE"PLUMBING"
HDL_TAP"TRUE";
"B \NAC \NWC"6;
"S \NAC"
BN"11"91;
%"TAP"
"1","(-6025,2475)","0","mstr_standard","I45";
;
CDS_LIB"mstr_standard"
BODY_TYPE"PLUMBING"
HDL_TAP"TRUE";
"B \NAC \NWC"6;
"S \NAC"
BN"12"92;
%"TAP"
"1","(-6025,2525)","0","mstr_standard","I46";
;
CDS_LIB"mstr_standard"
BODY_TYPE"PLUMBING"
HDL_TAP"TRUE";
"B \NAC \NWC"6;
"S \NAC"
BN"13"93;
%"TAP"
"1","(-6025,2575)","0","mstr_standard","I47";
;
CDS_LIB"mstr_standard"
BODY_TYPE"PLUMBING"
HDL_TAP"TRUE";
"B \NAC \NWC"6;
"S \NAC"
BN"14"94;
%"TAP"
"1","(-6025,2625)","0","mstr_standard","I48";
;
CDS_LIB"mstr_standard"
BODY_TYPE"PLUMBING"
HDL_TAP"TRUE";
"B \NAC \NWC"6;
"S \NAC"
BN"15"95;
%"TAP"
"1","(-6025,2675)","0","mstr_standard","I49";
;
CDS_LIB"mstr_standard"
BODY_TYPE"PLUMBING"
HDL_TAP"TRUE";
"B \NAC \NWC"6;
"S \NAC"
BN"16"96;
%"TAP"
"1","(-6025,2725)","0","mstr_standard","I50";
;
CDS_LIB"mstr_standard"
BODY_TYPE"PLUMBING"
HDL_TAP"TRUE";
"B \NAC \NWC"6;
"S \NAC"
BN"17"97;
%"TAP"
"1","(-6025,2775)","0","mstr_standard","I51";
;
CDS_LIB"mstr_standard"
BODY_TYPE"PLUMBING"
HDL_TAP"TRUE";
"B \NAC \NWC"6;
"S \NAC"
BN"18"98;
%"TAP"
"1","(-6025,2825)","0","mstr_standard","I52";
;
CDS_LIB"mstr_standard"
BODY_TYPE"PLUMBING"
HDL_TAP"TRUE";
"B \NAC \NWC"6;
"S \NAC"
BN"19"99;
%"TAP"
"1","(-6025,2875)","0","mstr_standard","I53";
;
CDS_LIB"mstr_standard"
BODY_TYPE"PLUMBING"
HDL_TAP"TRUE";
"B \NAC \NWC"6;
"S \NAC"
BN"20"100;
%"TAP"
"1","(-6025,2925)","0","mstr_standard","I54";
;
CDS_LIB"mstr_standard"
BODY_TYPE"PLUMBING"
HDL_TAP"TRUE";
"B \NAC \NWC"6;
"S \NAC"
BN"21"101;
%"TAP"
"1","(-6025,2975)","0","mstr_standard","I55";
;
CDS_LIB"mstr_standard"
BODY_TYPE"PLUMBING"
HDL_TAP"TRUE";
"B \NAC \NWC"6;
"S \NAC"
BN"22"102;
%"TAP"
"1","(-6025,3025)","0","mstr_standard","I56";
;
CDS_LIB"mstr_standard"
BODY_TYPE"PLUMBING"
HDL_TAP"TRUE";
"B \NAC \NWC"6;
"S \NAC"
BN"23"103;
%"TAP"
"1","(-6025,3075)","0","mstr_standard","I57";
;
CDS_LIB"mstr_standard"
BODY_TYPE"PLUMBING"
HDL_TAP"TRUE";
"B \NAC \NWC"6;
"S \NAC"
BN"24"104;
%"TAP"
"1","(-6025,3125)","0","mstr_standard","I58";
;
CDS_LIB"mstr_standard"
BODY_TYPE"PLUMBING"
HDL_TAP"TRUE";
"B \NAC \NWC"6;
"S \NAC"
BN"25"105;
%"TAP"
"1","(-6025,3175)","0","mstr_standard","I59";
;
CDS_LIB"mstr_standard"
BODY_TYPE"PLUMBING"
HDL_TAP"TRUE";
"B \NAC \NWC"6;
"S \NAC"
BN"26"106;
%"TAP"
"1","(-6025,3225)","0","mstr_standard","I60";
;
CDS_LIB"mstr_standard"
BODY_TYPE"PLUMBING"
HDL_TAP"TRUE";
"B \NAC \NWC"6;
"S \NAC"
BN"27"107;
%"TAP"
"1","(-6025,3275)","0","mstr_standard","I61";
;
CDS_LIB"mstr_standard"
BODY_TYPE"PLUMBING"
HDL_TAP"TRUE";
"B \NAC \NWC"6;
"S \NAC"
BN"28"108;
%"TAP"
"1","(-6025,3325)","0","mstr_standard","I62";
;
CDS_LIB"mstr_standard"
BODY_TYPE"PLUMBING"
HDL_TAP"TRUE";
"B \NAC \NWC"6;
"S \NAC"
BN"29"109;
%"TAP"
"1","(-6025,3375)","0","mstr_standard","I63";
;
CDS_LIB"mstr_standard"
BODY_TYPE"PLUMBING"
HDL_TAP"TRUE";
"B \NAC \NWC"6;
"S \NAC"
BN"30"110;
%"TAP"
"1","(-7725,3425)","2","mstr_standard","I71";
;
CDS_LIB"mstr_standard"
BODY_TYPE"PLUMBING"
HDL_TAP"TRUE";
"B \NAC \NWC"1;
"S \NAC"
BN"2"155;
%"TAP"
"1","(-7725,3475)","2","mstr_standard","I72";
;
CDS_LIB"mstr_standard"
BODY_TYPE"PLUMBING"
HDL_TAP"TRUE";
"B \NAC \NWC"1;
"S \NAC"
BN"3"156;
%"TAP"
"1","(-7725,3575)","2","mstr_standard","I73";
;
CDS_LIB"mstr_standard"
BODY_TYPE"PLUMBING"
HDL_TAP"TRUE";
"B \NAC \NWC"1;
"S \NAC"
BN"5"157;
%"TAP"
"1","(-7725,3625)","2","mstr_standard","I74";
;
CDS_LIB"mstr_standard"
BODY_TYPE"PLUMBING"
HDL_TAP"TRUE";
"B \NAC \NWC"1;
"S \NAC"
BN"6"158;
%"TAP"
"1","(-7725,3525)","2","mstr_standard","I75";
;
CDS_LIB"mstr_standard"
BODY_TYPE"PLUMBING"
HDL_TAP"TRUE";
"B \NAC \NWC"1;
"S \NAC"
BN"4"175;
%"TAP"
"1","(-7725,3675)","2","mstr_standard","I76";
;
CDS_LIB"mstr_standard"
BODY_TYPE"PLUMBING"
HDL_TAP"TRUE";
"B \NAC \NWC"1;
"S \NAC"
BN"7"176;
%"TAP"
"1","(-7725,4375)","2","mstr_standard","I77";
;
CDS_LIB"mstr_standard"
BODY_TYPE"PLUMBING"
HDL_TAP"TRUE";
"B \NAC \NWC"3;
"S \NAC"
BN"0"171;
%"TAP"
"1","(-7725,4425)","2","mstr_standard","I78";
;
CDS_LIB"mstr_standard"
BODY_TYPE"PLUMBING"
HDL_TAP"TRUE";
"B \NAC \NWC"3;
"S \NAC"
BN"1"169;
%"TAP"
"1","(-7725,4475)","2","mstr_standard","I79";
;
CDS_LIB"mstr_standard"
BODY_TYPE"PLUMBING"
HDL_TAP"TRUE";
"B \NAC \NWC"3;
"S \NAC"
BN"2"167;
%"TAP"
"1","(-7725,4525)","2","mstr_standard","I80";
;
CDS_LIB"mstr_standard"
BODY_TYPE"PLUMBING"
HDL_TAP"TRUE";
"B \NAC \NWC"3;
"S \NAC"
BN"3"165;
%"TAP"
"1","(-7725,4575)","2","mstr_standard","I81";
;
CDS_LIB"mstr_standard"
BODY_TYPE"PLUMBING"
HDL_TAP"TRUE";
"B \NAC \NWC"3;
"S \NAC"
BN"4"163;
%"TAP"
"1","(-7725,4675)","2","mstr_standard","I82";
;
CDS_LIB"mstr_standard"
BODY_TYPE"PLUMBING"
HDL_TAP"TRUE";
"B \NAC \NWC"3;
"S \NAC"
BN"6"159;
%"TAP"
"1","(-7725,4625)","2","mstr_standard","I83";
;
CDS_LIB"mstr_standard"
BODY_TYPE"PLUMBING"
HDL_TAP"TRUE";
"B \NAC \NWC"3;
"S \NAC"
BN"5"161;
%"TAP"
"1","(-7725,4825)","2","mstr_standard","I84";
;
CDS_LIB"mstr_standard"
BODY_TYPE"PLUMBING"
HDL_TAP"TRUE";
"B \NAC \NWC"2;
"S \NAC"
BN"1"170;
%"TAP"
"1","(-7725,4875)","2","mstr_standard","I85";
;
CDS_LIB"mstr_standard"
BODY_TYPE"PLUMBING"
HDL_TAP"TRUE";
"B \NAC \NWC"2;
"S \NAC"
BN"2"168;
%"TAP"
"1","(-7725,4925)","2","mstr_standard","I86";
;
CDS_LIB"mstr_standard"
BODY_TYPE"PLUMBING"
HDL_TAP"TRUE";
"B \NAC \NWC"2;
"S \NAC"
BN"3"166;
%"TAP"
"1","(-7725,4775)","2","mstr_standard","I87";
;
CDS_LIB"mstr_standard"
BODY_TYPE"PLUMBING"
HDL_TAP"TRUE";
"B \NAC \NWC"2;
"S \NAC"
BN"0"172;
%"TAP"
"1","(-7725,5025)","2","mstr_standard","I88";
;
CDS_LIB"mstr_standard"
BODY_TYPE"PLUMBING"
HDL_TAP"TRUE";
"B \NAC \NWC"2;
"S \NAC"
BN"5"162;
%"TAP"
"1","(-7725,5075)","2","mstr_standard","I89";
;
CDS_LIB"mstr_standard"
BODY_TYPE"PLUMBING"
HDL_TAP"TRUE";
"B \NAC \NWC"2;
"S \NAC"
BN"6"160;
%"VCC_CORE"
"1","(-8500,3100)","0","mstr_symbols","I9";
;
HDL_POWER"P3V3_STBY"
CDS_LIB"mstr_symbols"
VOLTAGE"3.3"
ROOM"PVCCINFAON_CPU0_CTRL";
"A"18;
%"TAP"
"1","(-7725,4975)","2","mstr_standard","I90";
;
CDS_LIB"mstr_standard"
BODY_TYPE"PLUMBING"
HDL_TAP"TRUE";
"B \NAC \NWC"2;
"S \NAC"
BN"4"164;
%"TAP"
"1","(-6025,3425)","0","mstr_standard","I91";
;
CDS_LIB"mstr_standard"
BODY_TYPE"PLUMBING"
HDL_TAP"TRUE";
"B \NAC \NWC"6;
"S \NAC"
BN"31"111;
%"TAP"
"1","(-6025,3525)","0","mstr_standard","I92";
;
CDS_LIB"mstr_standard"
BODY_TYPE"PLUMBING"
HDL_TAP"TRUE";
"B \NAC \NWC"5;
"S \NAC"
BN"0"112;
%"TAP"
"1","(-6025,3575)","0","mstr_standard","I93";
;
CDS_LIB"mstr_standard"
BODY_TYPE"PLUMBING"
HDL_TAP"TRUE";
"B \NAC \NWC"5;
"S \NAC"
BN"1"113;
%"TAP"
"1","(-6025,3625)","0","mstr_standard","I94";
;
CDS_LIB"mstr_standard"
BODY_TYPE"PLUMBING"
HDL_TAP"TRUE";
"B \NAC \NWC"5;
"S \NAC"
BN"2"114;
%"TAP"
"1","(-6025,3675)","0","mstr_standard","I95";
;
CDS_LIB"mstr_standard"
BODY_TYPE"PLUMBING"
HDL_TAP"TRUE";
"B \NAC \NWC"5;
"S \NAC"
BN"3"115;
%"TAP"
"1","(-6025,3725)","0","mstr_standard","I96";
;
CDS_LIB"mstr_standard"
BODY_TYPE"PLUMBING"
HDL_TAP"TRUE";
"B \NAC \NWC"5;
"S \NAC"
BN"4"116;
%"TAP"
"1","(-6025,3775)","0","mstr_standard","I97";
;
CDS_LIB"mstr_standard"
BODY_TYPE"PLUMBING"
HDL_TAP"TRUE";
"B \NAC \NWC"5;
"S \NAC"
BN"5"117;
%"TAP"
"1","(-6025,3825)","0","mstr_standard","I98";
;
CDS_LIB"mstr_standard"
BODY_TYPE"PLUMBING"
HDL_TAP"TRUE";
"B \NAC \NWC"5;
"S \NAC"
BN"6"118;
%"TAP"
"1","(-6025,3875)","0","mstr_standard","I99";
;
CDS_LIB"mstr_standard"
BODY_TYPE"PLUMBING"
HDL_TAP"TRUE";
"B \NAC \NWC"5;
"S \NAC"
BN"7"119;
END.
